# SCM (Grand Teton) — schematic netlist excerpt (pin names and nets, part order shuffled) for the footprints in the layout excerpt that follows; sources: Cadence DE-HDL packaged netlist, KiCad conversion of 12092022_DA0F0TMDCD0_F0T_Management_Board_D_brd_V3_OCP.brd

C40  Q_CAP  4.7UF 25V 10% X6S  pkg C0603  page 15 : A = P1V8_BMC_USB2AV18 ; B = GND
C284  Q_CAP  0.1UF 25V 10% X7R  pkg 0402  page 17 : A = ADCVREFEXT0 ; B = GND

(kicad_pcb
	(version 20260206)
	(generator "pcbnew")
	(generator_version "10.0")
	(general
		(thickness 1.6)
		(legacy_teardrops no)
	)
	(paper "A4")
	(title_block
		(title "12092022_DA0F0TMDCD0_F0T_Management_Board_D_brd_V3_OCP.brd")
		(comment 1 "Grand Teton / footprints 905-906 of 1440")
	)
	(layers
		(0 "F.Cu" signal "TOP")
		(4 "In1.Cu" signal "GND")
		(6 "In2.Cu" signal "IN1")
		(8 "In3.Cu" signal "GND1")
		(10 "In4.Cu" signal "IN2")
		(12 "In5.Cu" signal "VCC")
		(14 "In6.Cu" signal "VCC1")
		(16 "In7.Cu" signal "IN3")
		(18 "In8.Cu" signal "GND2")
		(20 "In9.Cu" signal "IN4")
		(22 "In10.Cu" signal "GND3")
		(2 "B.Cu" signal "BOTTOM")
		(9 "F.Adhes" user "F.Adhesive")
		(11 "B.Adhes" user "B.Adhesive")
		(13 "F.Paste" user "Package Geometry/Pastemask Top")
		(15 "B.Paste" user "Package Geometry/Pastemask Bottom")
		(5 "F.SilkS" user "Ref Des/Silkscreen Top")
		(7 "B.SilkS" user "Ref Des/Silkscreen Bottom")
		(1 "F.Mask" user "Board Geometry/Soldermask Top")
		(3 "B.Mask" user "Board Geometry/Soldermask Bottom")
		(17 "Dwgs.User" user "User.Drawings")
		(19 "Cmts.User" user "User.Comments")
		(21 "Eco1.User" user "User.Eco1")
		(23 "Eco2.User" user "User.Eco2")
		(25 "Edge.Cuts" user "Board Geometry/Outline")
		(27 "Margin" user)
		(31 "F.CrtYd" user "Package Geometry/Place Bound Top")
		(29 "B.CrtYd" user "Package Geometry/Place Bound Bottom")
		(35 "F.Fab" user "Ref Des/Assembly Top")
		(33 "B.Fab" user "Ref Des/Assembly Bottom")
	)
	(footprint ""
		(layer "B.Cu")
		(at 49.39919 -60.207652 -90)
		(property "Reference" "C284"
			(at 0 0 90)
			(layer "B.SilkS")
			(hide yes)
			(effects
				(font
					(size 1.27 1.27)
				)
				(justify mirror)
			)
		)
		(property "Value" ""
			(at 0 0 90)
			(layer "B.Fab")
			(effects
				(font
					(size 1.27 1.27)
				)
				(justify mirror)
			)
		)
		(duplicate_pad_numbers_are_jumpers no)
		(fp_line
			(start -0.7874 0.4064)
			(end 0.7874 0.4064)
			(stroke
				(width 0.1524)
				(type default)
			)
			(layer "B.SilkS")
		)
		(fp_line
			(start 0.7874 0.4064)
			(end 0.7874 -0.4064)
			(stroke
				(width 0.1524)
				(type default)
			)
			(layer "B.SilkS")
		)
		(fp_line
			(start -0.7874 -0.4064)
			(end -0.7874 0.4064)
			(stroke
				(width 0.1524)
				(type default)
			)
			(layer "B.SilkS")
		)
		(fp_line
			(start 0.7874 -0.4064)
			(end -0.7874 -0.4064)
			(stroke
				(width 0.1524)
				(type default)
			)
			(layer "B.SilkS")
		)
		(fp_line
			(start -0.67945 0.3048)
			(end -0.120396 0.3048)
			(stroke
				(width 0.1)
				(type default)
			)
			(layer "B.Fab")
		)
		(fp_line
			(start -0.120396 0.3048)
			(end -0.120396 0.2794)
			(stroke
				(width 0.1)
				(type default)
			)
			(layer "B.Fab")
		)
		(fp_line
			(start 0.12065 0.3048)
			(end 0.67945 0.3048)
			(stroke
				(width 0.1)
				(type default)
			)
			(layer "B.Fab")
		)
		(fp_line
			(start 0.67945 0.3048)
			(end 0.67945 -0.305054)
			(stroke
				(width 0.1)
				(type default)
			)
			(layer "B.Fab")
		)
		(fp_line
			(start -0.120396 0.2794)
			(end 0.12065 0.2794)
			(stroke
				(width 0.1)
				(type default)
			)
			(layer "B.Fab")
		)
		(fp_line
			(start 0.12065 0.2794)
			(end 0.12065 0.3048)
			(stroke
				(width 0.1)
				(type default)
			)
			(layer "B.Fab")
		)
		(fp_line
			(start -0.12065 -0.2794)
			(end -0.12065 -0.3048)
			(stroke
				(width 0.1)
				(type default)
			)
			(layer "B.Fab")
		)
		(fp_line
			(start 0.12065 -0.2794)
			(end -0.12065 -0.2794)
			(stroke
				(width 0.1)
				(type default)
			)
			(layer "B.Fab")
		)
		(fp_line
			(start -0.67945 -0.3048)
			(end -0.67945 0.3048)
			(stroke
				(width 0.1)
				(type default)
			)
			(layer "B.Fab")
		)
		(fp_line
			(start -0.12065 -0.3048)
			(end -0.67945 -0.3048)
			(stroke
				(width 0.1)
				(type default)
			)
			(layer "B.Fab")
		)
		(fp_line
			(start 0.12065 -0.305054)
			(end 0.12065 -0.2794)
			(stroke
				(width 0.1)
				(type default)
			)
			(layer "B.Fab")
		)
		(fp_line
			(start 0.67945 -0.305054)
			(end 0.12065 -0.305054)
			(stroke
				(width 0.1)
				(type default)
			)
			(layer "B.Fab")
		)
		(pad "1" smd circle
			(at 0.40005 0 90)
			(size 0 0)
			(layers "B.Cu" "B.Mask" "B.Paste")
			(net "ADCVREFEXT0")
		)
		(pad "2" smd circle
			(at -0.40005 0 90)
			(size 0 0)
			(layers "B.Cu" "B.Mask" "B.Paste")
			(net "GND")
		)
	)
	(footprint ""
		(layer "B.Cu")
		(at 71.374 -41.402 -90)
		(property "Reference" "C40"
			(at 0 0 90)
			(layer "B.SilkS")
			(hide yes)
			(effects
				(font
					(size 1.27 1.27)
				)
				(justify mirror)
			)
		)
		(property "Value" ""
			(at 0 0 90)
			(layer "B.Fab")
			(effects
				(font
					(size 1.27 1.27)
				)
				(justify mirror)
			)
		)
		(duplicate_pad_numbers_are_jumpers no)
		(fp_line
			(start -1.2954 0.5842)
			(end 1.2954 0.5842)
			(stroke
				(width 0.1524)
				(type default)
			)
			(layer "B.SilkS")
		)
		(fp_line
			(start 1.2954 0.5842)
			(end 1.2954 -0.5842)
			(stroke
				(width 0.1524)
				(type default)
			)
			(layer "B.SilkS")
		)
		(fp_line
			(start -1.2954 -0.5842)
			(end -1.2954 0.5842)
			(stroke
				(width 0.1524)
				(type default)
			)
			(layer "B.SilkS")
		)
		(fp_line
			(start 0 -0.5842)
			(end 0 0.5842)
			(stroke
				(width 0.1524)
				(type default)
			)
			(layer "B.SilkS")
		)
		(fp_line
			(start 1.2954 -0.5842)
			(end -1.2954 -0.5842)
			(stroke
				(width 0.1524)
				(type default)
			)
			(layer "B.SilkS")
		)
		(fp_line
			(start -0.8636 0.4572)
			(end 0.8636 0.4572)
			(stroke
				(width 0.1)
				(type default)
			)
			(layer "B.Fab")
		)
		(fp_line
			(start 0.8636 0.4572)
			(end 0.8636 0.4064)
			(stroke
				(width 0.1)
				(type default)
			)
			(layer "B.Fab")
		)
		(fp_line
			(start -1.1938 0.4064)
			(end -0.8636 0.4064)
			(stroke
				(width 0.1)
				(type default)
			)
			(layer "B.Fab")
		)
		(fp_line
			(start -0.8636 0.4064)
			(end -0.8636 0.4572)
			(stroke
				(width 0.1)
				(type default)
			)
			(layer "B.Fab")
		)
		(fp_line
			(start 0.8636 0.4064)
			(end 1.1938 0.4064)
			(stroke
				(width 0.1)
				(type default)
			)
			(layer "B.Fab")
		)
		(fp_line
			(start 1.1938 0.4064)
			(end 1.1938 -0.4064)
			(stroke
				(width 0.1)
				(type default)
			)
			(layer "B.Fab")
		)
		(fp_line
			(start -1.1938 -0.4064)
			(end -1.1938 0.4064)
			(stroke
				(width 0.1)
				(type default)
			)
			(layer "B.Fab")
		)
		(fp_line
			(start -0.8636 -0.4064)
			(end -1.1938 -0.4064)
			(stroke
				(width 0.1)
				(type default)
			)
			(layer "B.Fab")
		)
		(fp_line
			(start 0.8636 -0.4064)
			(end 0.8636 -0.4572)
			(stroke
				(width 0.1)
				(type default)
			)
			(layer "B.Fab")
		)
		(fp_line
			(start 1.1938 -0.4064)
			(end 0.8636 -0.4064)
			(stroke
				(width 0.1)
				(type default)
			)
			(layer "B.Fab")
		)
		(fp_line
			(start -0.8636 -0.4572)
			(end -0.8636 -0.4064)
			(stroke
				(width 0.1)
				(type default)
			)
			(layer "B.Fab")
		)
		(fp_line
			(start 0.8636 -0.4572)
			(end -0.8636 -0.4572)
			(stroke
				(width 0.1)
				(type default)
			)
			(layer "B.Fab")
		)
		(pad "1" smd rect
			(at 0.7366 0 180)
			(size 0.7112 0.8128)
			(layers "B.Cu" "B.Mask" "B.Paste")
			(net "P1V8_BMC_USB2AV18")
		)
		(pad "2" smd rect
			(at -0.7366 0 180)
			(size 0.7112 0.8128)
			(layers "B.Cu" "B.Mask" "B.Paste")
			(net "GND")
		)
	)
)
